# S9S_MB_2U (Grand Teton) — schematic netlist excerpt (pin names and nets, part order shuffled) for the footprints in the layout excerpt that follows; sources: Cadence DE-HDL packaged netlist, KiCad conversion of 03242023_DA0F0TMBIJ0_F0T_Motherboard_J_brd_V01_OCP.brd

C981  Q_CAP  10UF 6.3V 20% X6S  pkg C0402  page 74 : A = PVCCIN_CPU0 ; B = GND
R2671  Q_RES  33.2 1% CHIP  pkg 0402LF  page 234 : A = SMB_BMC_SWB_BUF_R_SCL ; B = SMB_BMC_SWB_BUF_SCL

(kicad_pcb
	(version 20260206)
	(generator "pcbnew")
	(generator_version "10.0")
	(general
		(thickness 1.6)
		(legacy_teardrops no)
	)
	(paper "A4")
	(title_block
		(title "03242023_DA0F0TMBIJ0_F0T_Motherboard_J_brd_V01_OCP.brd")
		(comment 1 "Grand Teton / footprints 3179-3180 of 6105")
	)
	(layers
		(0 "F.Cu" signal "TOP")
		(4 "In1.Cu" signal "GND")
		(6 "In2.Cu" signal "IN1")
		(8 "In3.Cu" signal "GND1")
		(10 "In4.Cu" signal "IN2")
		(12 "In5.Cu" signal "GND2")
		(14 "In6.Cu" signal "IN3")
		(16 "In7.Cu" signal "GND3")
		(18 "In8.Cu" signal "VCC")
		(20 "In9.Cu" signal "VCC1")
		(22 "In10.Cu" signal "GND4")
		(24 "In11.Cu" signal "IN4")
		(26 "In12.Cu" signal "GND5")
		(28 "In13.Cu" signal "IN5")
		(30 "In14.Cu" signal "GND6")
		(32 "In15.Cu" signal "IN6")
		(34 "In16.Cu" signal "GND7")
		(2 "B.Cu" signal "BOTTOM")
		(9 "F.Adhes" user "F.Adhesive")
		(11 "B.Adhes" user "B.Adhesive")
		(13 "F.Paste" user "Package Geometry/Pastemask Top")
		(15 "B.Paste" user "Package Geometry/Pastemask Bottom")
		(5 "F.SilkS" user "Ref Des/Silkscreen Top")
		(7 "B.SilkS" user "Ref Des/Silkscreen Bottom")
		(1 "F.Mask" user "Board Geometry/Soldermask Top")
		(3 "B.Mask" user "Board Geometry/Soldermask Bottom")
		(17 "Dwgs.User" user "User.Drawings")
		(19 "Cmts.User" user "User.Comments")
		(21 "Eco1.User" user "User.Eco1")
		(23 "Eco2.User" user "User.Eco2")
		(25 "Edge.Cuts" user "Board Geometry/Outline")
		(27 "Margin" user)
		(31 "F.CrtYd" user "Package Geometry/Place Bound Top")
		(29 "B.CrtYd" user "Package Geometry/Place Bound Bottom")
		(35 "F.Fab" user "Ref Des/Assembly Top")
		(33 "B.Fab" user "Ref Des/Assembly Bottom")
	)
	(footprint ""
		(layer "F.Cu")
		(at 165.15715 -432.865276 90)
		(property "Reference" "R2671"
			(at 0 0 90)
			(layer "F.SilkS")
			(hide yes)
			(effects
				(font
					(size 1.27 1.27)
				)
			)
		)
		(property "Value" ""
			(at 0 0 90)
			(layer "F.Fab")
			(effects
				(font
					(size 1.27 1.27)
				)
			)
		)
		(duplicate_pad_numbers_are_jumpers no)
		(fp_line
			(start 0.7874 -0.4064)
			(end 0.7874 0.4064)
			(stroke
				(width 0.1524)
				(type default)
			)
			(layer "F.SilkS")
		)
		(fp_line
			(start -0.7874 -0.4064)
			(end 0.7874 -0.4064)
			(stroke
				(width 0.1524)
				(type default)
			)
			(layer "F.SilkS")
		)
		(fp_line
			(start 0.7874 0.4064)
			(end -0.7874 0.4064)
			(stroke
				(width 0.1524)
				(type default)
			)
			(layer "F.SilkS")
		)
		(fp_line
			(start -0.7874 0.4064)
			(end -0.7874 -0.4064)
			(stroke
				(width 0.1524)
				(type default)
			)
			(layer "F.SilkS")
		)
		(fp_line
			(start -0.12065 -0.305054)
			(end -0.12065 -0.2794)
			(stroke
				(width 0.1)
				(type default)
			)
			(layer "F.Fab")
		)
		(fp_line
			(start -0.67945 -0.305054)
			(end -0.12065 -0.305054)
			(stroke
				(width 0.1)
				(type default)
			)
			(layer "F.Fab")
		)
		(fp_line
			(start 0.67945 -0.3048)
			(end 0.67945 0.3048)
			(stroke
				(width 0.1)
				(type default)
			)
			(layer "F.Fab")
		)
		(fp_line
			(start 0.12065 -0.3048)
			(end 0.67945 -0.3048)
			(stroke
				(width 0.1)
				(type default)
			)
			(layer "F.Fab")
		)
		(fp_line
			(start 0.12065 -0.2794)
			(end 0.12065 -0.3048)
			(stroke
				(width 0.1)
				(type default)
			)
			(layer "F.Fab")
		)
		(fp_line
			(start -0.12065 -0.2794)
			(end 0.12065 -0.2794)
			(stroke
				(width 0.1)
				(type default)
			)
			(layer "F.Fab")
		)
		(fp_line
			(start 0.120396 0.2794)
			(end -0.12065 0.2794)
			(stroke
				(width 0.1)
				(type default)
			)
			(layer "F.Fab")
		)
		(fp_line
			(start -0.12065 0.2794)
			(end -0.12065 0.3048)
			(stroke
				(width 0.1)
				(type default)
			)
			(layer "F.Fab")
		)
		(fp_line
			(start 0.67945 0.3048)
			(end 0.120396 0.3048)
			(stroke
				(width 0.1)
				(type default)
			)
			(layer "F.Fab")
		)
		(fp_line
			(start 0.120396 0.3048)
			(end 0.120396 0.2794)
			(stroke
				(width 0.1)
				(type default)
			)
			(layer "F.Fab")
		)
		(fp_line
			(start -0.12065 0.3048)
			(end -0.67945 0.3048)
			(stroke
				(width 0.1)
				(type default)
			)
			(layer "F.Fab")
		)
		(fp_line
			(start -0.67945 0.3048)
			(end -0.67945 -0.305054)
			(stroke
				(width 0.1)
				(type default)
			)
			(layer "F.Fab")
		)
		(pad "1" smd circle
			(at -0.40005 0 90)
			(size 0 0)
			(layers "F.Cu" "F.Mask" "F.Paste")
			(net "SMB_BMC_SWB_BUF_R_SCL")
		)
		(pad "2" smd circle
			(at 0.40005 0 90)
			(size 0 0)
			(layers "F.Cu" "F.Mask" "F.Paste")
			(net "SMB_BMC_SWB_BUF_SCL")
		)
	)
	(footprint ""
		(layer "F.Cu")
		(at 367.44783 -249.320304 -90)
		(property "Reference" "C981"
			(at 0 0 270)
			(layer "F.SilkS")
			(hide yes)
			(effects
				(font
					(size 1.27 1.27)
				)
			)
		)
		(property "Value" ""
			(at 0 0 270)
			(layer "F.Fab")
			(effects
				(font
					(size 1.27 1.27)
				)
			)
		)
		(duplicate_pad_numbers_are_jumpers no)
		(fp_line
			(start -0.7874 0.4064)
			(end -0.7874 -0.4064)
			(stroke
				(width 0.1524)
				(type default)
			)
			(layer "F.SilkS")
		)
		(fp_line
			(start 0.7874 0.4064)
			(end -0.7874 0.4064)
			(stroke
				(width 0.1524)
				(type default)
			)
			(layer "F.SilkS")
		)
		(fp_line
			(start -0.7874 -0.4064)
			(end 0.7874 -0.4064)
			(stroke
				(width 0.1524)
				(type default)
			)
			(layer "F.SilkS")
		)
		(fp_line
			(start 0.7874 -0.4064)
			(end 0.7874 0.4064)
			(stroke
				(width 0.1524)
				(type default)
			)
			(layer "F.SilkS")
		)
		(fp_line
			(start -0.67945 0.3048)
			(end -0.67945 -0.305054)
			(stroke
				(width 0.1)
				(type default)
			)
			(layer "F.Fab")
		)
		(fp_line
			(start -0.12065 0.3048)
			(end -0.67945 0.3048)
			(stroke
				(width 0.1)
				(type default)
			)
			(layer "F.Fab")
		)
		(fp_line
			(start 0.120396 0.3048)
			(end 0.120396 0.2794)
			(stroke
				(width 0.1)
				(type default)
			)
			(layer "F.Fab")
		)
		(fp_line
			(start 0.67945 0.3048)
			(end 0.120396 0.3048)
			(stroke
				(width 0.1)
				(type default)
			)
			(layer "F.Fab")
		)
		(fp_line
			(start -0.12065 0.2794)
			(end -0.12065 0.3048)
			(stroke
				(width 0.1)
				(type default)
			)
			(layer "F.Fab")
		)
		(fp_line
			(start 0.120396 0.2794)
			(end -0.12065 0.2794)
			(stroke
				(width 0.1)
				(type default)
			)
			(layer "F.Fab")
		)
		(fp_line
			(start -0.12065 -0.2794)
			(end 0.12065 -0.2794)
			(stroke
				(width 0.1)
				(type default)
			)
			(layer "F.Fab")
		)
		(fp_line
			(start 0.12065 -0.2794)
			(end 0.12065 -0.3048)
			(stroke
				(width 0.1)
				(type default)
			)
			(layer "F.Fab")
		)
		(fp_line
			(start 0.12065 -0.3048)
			(end 0.67945 -0.3048)
			(stroke
				(width 0.1)
				(type default)
			)
			(layer "F.Fab")
		)
		(fp_line
			(start 0.67945 -0.3048)
			(end 0.67945 0.3048)
			(stroke
				(width 0.1)
				(type default)
			)
			(layer "F.Fab")
		)
		(fp_line
			(start -0.67945 -0.305054)
			(end -0.12065 -0.305054)
			(stroke
				(width 0.1)
				(type default)
			)
			(layer "F.Fab")
		)
		(fp_line
			(start -0.12065 -0.305054)
			(end -0.12065 -0.2794)
			(stroke
				(width 0.1)
				(type default)
			)
			(layer "F.Fab")
		)
		(pad "1" smd circle
			(at -0.40005 0 270)
			(size 0 0)
			(layers "F.Cu" "F.Mask" "F.Paste")
			(net "PVCCIN_CPU0")
		)
		(pad "2" smd circle
			(at 0.40005 0 270)
			(size 0 0)
			(layers "F.Cu" "F.Mask" "F.Paste")
			(net "GND")
		)
	)
)
